# BASEBOARD_FAB2 (Tioga Pass) — schematic netlist excerpt (pin names and nets, part order shuffled) for the footprints in the layout excerpt that follows; sources: Cadence DE-HDL packaged netlist, KiCad conversion of Wiwynn_Tioga_Pass_MB.brd

J9A3  SCONN60_C21100002  CONN  pkg SMLF  page 111
  IO1  = XDP_DEBUG_CONSENT_N
  IO2  = GND
  IO3  = XDP_PREQ_N
  IO4  = TP_XDP_CPU_OBSFN_C0
  IO5  = XDP_PRDY_N
  IO6  = XDP_SPI_PCH_MOSI_BOOT_HALT_N
  IO7  = GND
  IO8  = GND
  IO9  = TP_XDP_OBSDATA_A0
  IO10  = TP_XDP_CPU_OBSDATA_C0
  IO11  = TP_XDP_OBSDATA_A1
  IO12  = TP_XDP_CPU_OBSDATA_C1
  IO13  = GND
  IO14  = GND
  IO15  = TP_XDP_OBSDATA_A2
  IO16  = TP_XDP_CPU_OBSDATA_C2
  IO17  = TP_XDP_OBSDATA_A3
  IO18  = TP_XDP_CPU_OBSDATA_C3
  IO19  = GND
  IO20  = GND
  IO21  = TP_XDP_OBSFN_B0
  IO22  = XDP_OBSFN_B0_MBP6_N
  IO23  = TP_XDP_OBSFN_B1
  IO24  = XDP_OBSFN_B1_MBP7_N
  IO25  = GND
  IO26  = GND
  IO27  = TP_XDP_OBSDATA_B0
  IO28  = TP_XDP_CPU_OBSDATA_D0
  IO29  = TP_XDP_OBSDATA_B1
  IO30  = TP_XDP_CPU_OBSDATA_D1
  IO31  = GND
  IO32  = GND
  IO33  = TP_XDP_OBSDATA_B2
  IO34  = TP_XDP_CPU_OBSDATA_D2
  IO35  = TP_XDP_OBSDATA_B3
  IO36  = TP_XDP_CPU_OBSDATA_D3
  IO37  = GND
  IO38  = GND
  IO39  = XDP_RSMRST_N
  IO40  = CLK_100M_PCH_XDP_DP
  IO41  = XDP_PWRGD_RST_N
  IO42  = CLK_100M_PCH_XDP_DN
  IO43  = P1V05_PCH_STBY
  IO44  = P1V05_PCH_STBY
  IO45  = XDP_CPU_PWR_DEBUG_N
  IO46  = XDP_ITP_PMODE
  IO47  = XDP_SYSPWROK
  IO48  = XDP_RST_CO_N
  IO49  = GND
  IO50  = GND
  IO51  = SMB_HOST_STBY_LVC3_SDA
  IO52  = XDP_TDO
  IO53  = SMB_HOST_STBY_LVC3_SCL
  IO54  = XDP_TRST_N
  IO55  = XDP_PCH_TCK1
  IO56  = XDP_TDI
  IO57  = XDP_CPU_TCK0
  IO58  = XDP_TMS
  IO59  = GND
  IO60  = XDP_PRESENT_N

(kicad_pcb
	(version 20260206)
	(generator "pcbnew")
	(generator_version "10.0")
	(general
		(thickness 1.6)
		(legacy_teardrops no)
	)
	(paper "A4")
	(title_block
		(title "Wiwynn_Tioga_Pass_MB.brd")
		(comment 1 "Tioga Pass / footprint 867 of 4770 (J9A3), pads 47-62 of 62")
	)
	(layers
		(0 "F.Cu" signal "TOP")
		(4 "In1.Cu" signal "L2GND")
		(6 "In2.Cu" signal "L3")
		(8 "In3.Cu" signal "L4GND")
		(10 "In4.Cu" signal "L5")
		(12 "In5.Cu" signal "L6GND")
		(14 "In6.Cu" signal "L7VCC")
		(16 "In7.Cu" signal "L8VCC")
		(18 "In8.Cu" signal "L9GND")
		(20 "In9.Cu" signal "L10")
		(22 "In10.Cu" signal "L11GND")
		(24 "In11.Cu" signal "L12")
		(26 "In12.Cu" signal "L13GND")
		(2 "B.Cu" signal "BOTTOM")
		(9 "F.Adhes" user "F.Adhesive")
		(11 "B.Adhes" user "B.Adhesive")
		(13 "F.Paste" user "Package Geometry/Pastemask Top")
		(15 "B.Paste" user "Package Geometry/Pastemask Bottom")
		(5 "F.SilkS" user "Ref Des/Silkscreen Top")
		(7 "B.SilkS" user "Ref Des/Silkscreen Bottom")
		(1 "F.Mask" user "Board Geometry/Soldermask Top")
		(3 "B.Mask" user "Board Geometry/Soldermask Bottom")
		(17 "Dwgs.User" user "User.Drawings")
		(19 "Cmts.User" user "User.Comments")
		(21 "Eco1.User" user "User.Eco1")
		(23 "Eco2.User" user "User.Eco2")
		(25 "Edge.Cuts" user "Board Geometry/Outline")
		(27 "Margin" user)
		(31 "F.CrtYd" user "Package Geometry/Place Bound Top")
		(29 "B.CrtYd" user "Package Geometry/Place Bound Bottom")
		(35 "F.Fab" user "Ref Des/Assembly Top")
		(33 "B.Fab" user "Ref Des/Assembly Bottom")
	)
	(footprint ""
		(layer "F.Cu")
		(at 462.980532 -135.71982 90.001)
		(property "Reference" "J9A3"
			(at 3.15304 -8.221925 90.001)
			(unlocked yes)
			(layer "F.SilkS")
			(effects
				(font
					(size 0.7874 0.5842)
					(thickness 0.1524)
				)
				(justify left)
			)
		)
		(property "Value" ""
			(at 0 0 90.001)
			(layer "F.Fab")
			(effects
				(font
					(size 1.27 1.27)
				)
			)
		)
		(duplicate_pad_numbers_are_jumpers no)
		(pad "45" smd rect
			(at 10.999978 0 90.001)
			(size 0.2794 2.286)
			(layers "F.Cu" "F.Mask" "F.Paste")
			(net "XDP_CPU_PWR_DEBUG_N")
		)
		(pad "46" smd rect
			(at 10.999978 -5.727954 90.001)
			(size 0.2794 2.286)
			(layers "F.Cu" "F.Mask" "F.Paste")
			(net "XDP_ITP_PMODE")
		)
		(pad "47" smd rect
			(at 11.500104 0 90.001)
			(size 0.2794 2.286)
			(layers "F.Cu" "F.Mask" "F.Paste")
			(net "XDP_SYSPWROK")
		)
		(pad "48" smd rect
			(at 11.500104 -5.727954 90.001)
			(size 0.2794 2.286)
			(layers "F.Cu" "F.Mask" "F.Paste")
			(net "XDP_RST_CO_N")
		)
		(pad "49" smd rect
			(at 11.999976 0 90.001)
			(size 0.2794 2.286)
			(layers "F.Cu" "F.Mask" "F.Paste")
			(net "GND")
		)
		(pad "50" smd rect
			(at 11.999976 -5.727954 90.001)
			(size 0.2794 2.286)
			(layers "F.Cu" "F.Mask" "F.Paste")
			(net "GND")
		)
		(pad "51" smd rect
			(at 12.500102 0 90.001)
			(size 0.2794 2.286)
			(layers "F.Cu" "F.Mask" "F.Paste")
			(net "SMB_HOST_STBY_LVC3_SDA")
		)
		(pad "52" smd rect
			(at 12.500102 -5.727954 90.001)
			(size 0.2794 2.286)
			(layers "F.Cu" "F.Mask" "F.Paste")
			(net "XDP_TDO")
		)
		(pad "53" smd rect
			(at 12.999974 0 90.001)
			(size 0.2794 2.286)
			(layers "F.Cu" "F.Mask" "F.Paste")
			(net "SMB_HOST_STBY_LVC3_SCL")
		)
		(pad "54" smd rect
			(at 12.999974 -5.727954 90.001)
			(size 0.2794 2.286)
			(layers "F.Cu" "F.Mask" "F.Paste")
			(net "XDP_TRST_N")
		)
		(pad "55" smd rect
			(at 13.5001 0 90.001)
			(size 0.2794 2.286)
			(layers "F.Cu" "F.Mask" "F.Paste")
			(net "XDP_PCH_TCK1")
		)
		(pad "56" smd rect
			(at 13.5001 -5.727954 90.001)
			(size 0.2794 2.286)
			(layers "F.Cu" "F.Mask" "F.Paste")
			(net "XDP_TDI")
		)
		(pad "57" smd rect
			(at 13.999972 0 90.001)
			(size 0.2794 2.286)
			(layers "F.Cu" "F.Mask" "F.Paste")
			(net "XDP_CPU_TCK0")
		)
		(pad "58" smd rect
			(at 13.999972 -5.727954 90.001)
			(size 0.2794 2.286)
			(layers "F.Cu" "F.Mask" "F.Paste")
			(net "XDP_TMS")
		)
		(pad "59" smd rect
			(at 14.500098 0 90.001)
			(size 0.2794 2.286)
			(layers "F.Cu" "F.Mask" "F.Paste")
			(net "GND")
		)
		(pad "60" smd rect
			(at 14.500098 -5.727954 90.001)
			(size 0.2794 2.286)
			(layers "F.Cu" "F.Mask" "F.Paste")
			(net "XDP_PRESENT_N")
		)
	)
)
